# ZAIUS-MB-EVT3-HW-EBOM-X00_20161228-add_2nd_source_X15-20170106-Final.xls — DEPOP_GA (bom)
| FOXCONN TECHNOLOGY GROUP |  |  |  |  |  |  |  |  |  |  |  |  |
| BILL OF MATERIAL |  |  |  |  |  |  |  |  |  |  |  |  |
| REV OF  BOM |  | CUSTOMER | <name> |  | CUSTOMER P/N |  | PRODUCT CODE |  | PWA  REV |  | DATE |  |
| Sourcing (Single/Sole/Multi) | Critical Commodity (Y or N) | Component Class (1, 2, other) | Customer PSL (Y or N) | Item Number | Foxconn P/N | Customer P/N | Part Description | Manufacturer  Full Name | Manufacturer  Part Number | Qty | RoHS Status | Location |
|  |  |  |  | 1 | 61010L300-017-G | - | RES,1KOhm,+/-1%,1/16W,G,SMD0402 | KOA SPEER ELECTRONICS, INC. | RK73H1ETTP1001F | 2 |  | R657,R660 |
|  |  |  |  | 2 | 610107A00-017-G | - | RES,0 Ohm,+/-5%,1/16W,G,SMD0402 | KOA SPEER ELECTRONICS, INC. | RK73Z1ETTP | 2 |  | R661,R662 |
|  |  |  |  | 3 | 3406AQH00-317-G |  | CONN,Header,Pin Header,1X6,V/T,Bla,2.54mm,G,SMD-6 | MOLEX | 87898-0656 | 1 |  | J_UART_LOM1 |
